(kicad_pcb
	(version 20260206)
	(generator "pcbnew")
	(generator_version "10.0")
	(general
		(thickness 1.6)
		(legacy_teardrops no)
	)
	(paper "A4")
	(title_block
		(title "12092022_DA0F0TFB6D0_F0T_FAN_BOARD_MP5048_D_brd_v02_OCP.brd")
		(comment 1 "Grand Teton / footprints 452-457 of 924")
	)
	(layers
		(0 "F.Cu" signal "TOP")
		(4 "In1.Cu" signal "GND")
		(6 "In2.Cu" signal "IN1")
		(8 "In3.Cu" signal "IN2")
		(10 "In4.Cu" signal "GND1")
		(2 "B.Cu" signal "BOTTOM")
		(9 "F.Adhes" user "F.Adhesive")
		(11 "B.Adhes" user "B.Adhesive")
		(13 "F.Paste" user "Package Geometry/Pastemask Top")
		(15 "B.Paste" user "Package Geometry/Pastemask Bottom")
		(5 "F.SilkS" user "Ref Des/Silkscreen Top")
		(7 "B.SilkS" user "Ref Des/Silkscreen Bottom")
		(1 "F.Mask" user "Board Geometry/Soldermask Top")
		(3 "B.Mask" user "Board Geometry/Soldermask Bottom")
		(17 "Dwgs.User" user "User.Drawings")
		(19 "Cmts.User" user "User.Comments")
		(21 "Eco1.User" user "User.Eco1")
		(23 "Eco2.User" user "User.Eco2")
		(25 "Edge.Cuts" user "Board Geometry/Outline")
		(27 "Margin" user)
		(31 "F.CrtYd" user "Package Geometry/Place Bound Top")
		(29 "B.CrtYd" user "Package Geometry/Place Bound Bottom")
		(35 "F.Fab" user "Ref Des/Assembly Top")
		(33 "B.Fab" user "Ref Des/Assembly Bottom")
	)
	(footprint ""
		(layer "F.Cu")
		(at 17.907 -165.481 180)
		(property "Reference" "R5497"
			(at 0 0 180)
			(layer "F.SilkS")
			(hide yes)
			(effects
				(font
					(size 1.27 1.27)
				)
			)
		)
		(property "Value" ""
			(at 0 0 180)
			(layer "F.Fab")
			(effects
				(font
					(size 1.27 1.27)
				)
			)
		)
		(duplicate_pad_numbers_are_jumpers no)
		(fp_line
			(start 0.7874 0.4064)
			(end -0.7874 0.4064)
			(stroke
				(width 0.1524)
				(type default)
			)
			(layer "F.SilkS")
		)
		(fp_line
			(start 0.7874 -0.4064)
			(end 0.7874 0.4064)
			(stroke
				(width 0.1524)
				(type default)
			)
			(layer "F.SilkS")
		)
		(fp_line
			(start -0.7874 0.4064)
			(end -0.7874 -0.4064)
			(stroke
				(width 0.1524)
				(type default)
			)
			(layer "F.SilkS")
		)
		(fp_line
			(start -0.7874 -0.4064)
			(end 0.7874 -0.4064)
			(stroke
				(width 0.1524)
				(type default)
			)
			(layer "F.SilkS")
		)
		(fp_line
			(start 0.67945 0.3048)
			(end 0.120396 0.3048)
			(stroke
				(width 0.1)
				(type default)
			)
			(layer "F.Fab")
		)
		(fp_line
			(start 0.67945 -0.3048)
			(end 0.67945 0.3048)
			(stroke
				(width 0.1)
				(type default)
			)
			(layer "F.Fab")
		)
		(fp_line
			(start 0.12065 -0.2794)
			(end 0.12065 -0.3048)
			(stroke
				(width 0.1)
				(type default)
			)
			(layer "F.Fab")
		)
		(fp_line
			(start 0.12065 -0.3048)
			(end 0.67945 -0.3048)
			(stroke
				(width 0.1)
				(type default)
			)
			(layer "F.Fab")
		)
		(fp_line
			(start 0.120396 0.3048)
			(end 0.120396 0.2794)
			(stroke
				(width 0.1)
				(type default)
			)
			(layer "F.Fab")
		)
		(fp_line
			(start 0.120396 0.2794)
			(end -0.12065 0.2794)
			(stroke
				(width 0.1)
				(type default)
			)
			(layer "F.Fab")
		)
		(fp_line
			(start -0.12065 0.3048)
			(end -0.67945 0.3048)
			(stroke
				(width 0.1)
				(type default)
			)
			(layer "F.Fab")
		)
		(fp_line
			(start -0.12065 0.2794)
			(end -0.12065 0.3048)
			(stroke
				(width 0.1)
				(type default)
			)
			(layer "F.Fab")
		)
		(fp_line
			(start -0.12065 -0.2794)
			(end 0.12065 -0.2794)
			(stroke
				(width 0.1)
				(type default)
			)
			(layer "F.Fab")
		)
		(fp_line
			(start -0.12065 -0.305054)
			(end -0.12065 -0.2794)
			(stroke
				(width 0.1)
				(type default)
			)
			(layer "F.Fab")
		)
		(fp_line
			(start -0.67945 0.3048)
			(end -0.67945 -0.305054)
			(stroke
				(width 0.1)
				(type default)
			)
			(layer "F.Fab")
		)
		(fp_line
			(start -0.67945 -0.305054)
			(end -0.12065 -0.305054)
			(stroke
				(width 0.1)
				(type default)
			)
			(layer "F.Fab")
		)
		(pad "1" smd circle
			(at -0.40005 0 180)
			(size 0 0)
			(layers "F.Cu" "F.Mask" "F.Paste")
			(net "FAN_2_PRESENT_R_N")
		)
		(pad "2" smd circle
			(at 0.40005 0 180)
			(size 0 0)
			(layers "F.Cu" "F.Mask" "F.Paste")
			(net "FAN_2_PRESENT_N")
		)
	)
	(footprint ""
		(layer "F.Cu")
		(at 38.6461 -126.238)
		(property "Reference" "R5582"
			(at 0 0 0)
			(layer "F.SilkS")
			(hide yes)
			(effects
				(font
					(size 1.27 1.27)
				)
			)
		)
		(property "Value" ""
			(at 0 0 0)
			(layer "F.Fab")
			(effects
				(font
					(size 1.27 1.27)
				)
			)
		)
		(duplicate_pad_numbers_are_jumpers no)
		(fp_line
			(start -0.7874 -0.4064)
			(end 0.7874 -0.4064)
			(stroke
				(width 0.1524)
				(type default)
			)
			(layer "F.SilkS")
		)
		(fp_line
			(start -0.7874 0.4064)
			(end -0.7874 -0.4064)
			(stroke
				(width 0.1524)
				(type default)
			)
			(layer "F.SilkS")
		)
		(fp_line
			(start 0.7874 -0.4064)
			(end 0.7874 0.4064)
			(stroke
				(width 0.1524)
				(type default)
			)
			(layer "F.SilkS")
		)
		(fp_line
			(start 0.7874 0.4064)
			(end -0.7874 0.4064)
			(stroke
				(width 0.1524)
				(type default)
			)
			(layer "F.SilkS")
		)
		(fp_line
			(start -0.67945 -0.305054)
			(end -0.12065 -0.305054)
			(stroke
				(width 0.1)
				(type default)
			)
			(layer "F.Fab")
		)
		(fp_line
			(start -0.67945 0.3048)
			(end -0.67945 -0.305054)
			(stroke
				(width 0.1)
				(type default)
			)
			(layer "F.Fab")
		)
		(fp_line
			(start -0.12065 -0.305054)
			(end -0.12065 -0.2794)
			(stroke
				(width 0.1)
				(type default)
			)
			(layer "F.Fab")
		)
		(fp_line
			(start -0.12065 -0.2794)
			(end 0.12065 -0.2794)
			(stroke
				(width 0.1)
				(type default)
			)
			(layer "F.Fab")
		)
		(fp_line
			(start -0.12065 0.2794)
			(end -0.12065 0.3048)
			(stroke
				(width 0.1)
				(type default)
			)
			(layer "F.Fab")
		)
		(fp_line
			(start -0.12065 0.3048)
			(end -0.67945 0.3048)
			(stroke
				(width 0.1)
				(type default)
			)
			(layer "F.Fab")
		)
		(fp_line
			(start 0.120396 0.2794)
			(end -0.12065 0.2794)
			(stroke
				(width 0.1)
				(type default)
			)
			(layer "F.Fab")
		)
		(fp_line
			(start 0.120396 0.3048)
			(end 0.120396 0.2794)
			(stroke
				(width 0.1)
				(type default)
			)
			(layer "F.Fab")
		)
		(fp_line
			(start 0.12065 -0.3048)
			(end 0.67945 -0.3048)
			(stroke
				(width 0.1)
				(type default)
			)
			(layer "F.Fab")
		)
		(fp_line
			(start 0.12065 -0.2794)
			(end 0.12065 -0.3048)
			(stroke
				(width 0.1)
				(type default)
			)
			(layer "F.Fab")
		)
		(fp_line
			(start 0.67945 -0.3048)
			(end 0.67945 0.3048)
			(stroke
				(width 0.1)
				(type default)
			)
			(layer "F.Fab")
		)
		(fp_line
			(start 0.67945 0.3048)
			(end 0.120396 0.3048)
			(stroke
				(width 0.1)
				(type default)
			)
			(layer "F.Fab")
		)
		(pad "1" smd rect
			(at -0.40005 0 180)
			(size 0.4572 0.508)
			(layers "F.Cu" "F.Mask" "F.Paste")
			(net "FAN_2_TACH_OL")
		)
		(pad "2" smd rect
			(at 0.40005 0 180)
			(size 0.4572 0.508)
			(layers "F.Cu" "F.Mask" "F.Paste")
			(net "FAN_2_TACH_OL_R2")
		)
	)
	(footprint ""
		(layer "F.Cu")
		(at 24.638 -189.23 180)
		(property "Reference" "C2083"
			(at 0 0 180)
			(layer "F.SilkS")
			(hide yes)
			(effects
				(font
					(size 1.27 1.27)
				)
			)
		)
		(property "Value" ""
			(at 0 0 180)
			(layer "F.Fab")
			(effects
				(font
					(size 1.27 1.27)
				)
			)
		)
		(duplicate_pad_numbers_are_jumpers no)
		(fp_line
			(start 0.7874 0.4064)
			(end -0.7874 0.4064)
			(stroke
				(width 0.1524)
				(type default)
			)
			(layer "F.SilkS")
		)
		(fp_line
			(start 0.7874 -0.4064)
			(end 0.7874 0.4064)
			(stroke
				(width 0.1524)
				(type default)
			)
			(layer "F.SilkS")
		)
		(fp_line
			(start -0.7874 0.4064)
			(end -0.7874 -0.4064)
			(stroke
				(width 0.1524)
				(type default)
			)
			(layer "F.SilkS")
		)
		(fp_line
			(start -0.7874 -0.4064)
			(end 0.7874 -0.4064)
			(stroke
				(width 0.1524)
				(type default)
			)
			(layer "F.SilkS")
		)
		(fp_line
			(start 0.67945 0.3048)
			(end 0.120396 0.3048)
			(stroke
				(width 0.1)
				(type default)
			)
			(layer "F.Fab")
		)
		(fp_line
			(start 0.67945 -0.3048)
			(end 0.67945 0.3048)
			(stroke
				(width 0.1)
				(type default)
			)
			(layer "F.Fab")
		)
		(fp_line
			(start 0.12065 -0.2794)
			(end 0.12065 -0.3048)
			(stroke
				(width 0.1)
				(type default)
			)
			(layer "F.Fab")
		)
		(fp_line
			(start 0.12065 -0.3048)
			(end 0.67945 -0.3048)
			(stroke
				(width 0.1)
				(type default)
			)
			(layer "F.Fab")
		)
		(fp_line
			(start 0.120396 0.3048)
			(end 0.120396 0.2794)
			(stroke
				(width 0.1)
				(type default)
			)
			(layer "F.Fab")
		)
		(fp_line
			(start 0.120396 0.2794)
			(end -0.12065 0.2794)
			(stroke
				(width 0.1)
				(type default)
			)
			(layer "F.Fab")
		)
		(fp_line
			(start -0.12065 0.3048)
			(end -0.67945 0.3048)
			(stroke
				(width 0.1)
				(type default)
			)
			(layer "F.Fab")
		)
		(fp_line
			(start -0.12065 0.2794)
			(end -0.12065 0.3048)
			(stroke
				(width 0.1)
				(type default)
			)
			(layer "F.Fab")
		)
		(fp_line
			(start -0.12065 -0.2794)
			(end 0.12065 -0.2794)
			(stroke
				(width 0.1)
				(type default)
			)
			(layer "F.Fab")
		)
		(fp_line
			(start -0.12065 -0.305054)
			(end -0.12065 -0.2794)
			(stroke
				(width 0.1)
				(type default)
			)
			(layer "F.Fab")
		)
		(fp_line
			(start -0.67945 0.3048)
			(end -0.67945 -0.305054)
			(stroke
				(width 0.1)
				(type default)
			)
			(layer "F.Fab")
		)
		(fp_line
			(start -0.67945 -0.305054)
			(end -0.12065 -0.305054)
			(stroke
				(width 0.1)
				(type default)
			)
			(layer "F.Fab")
		)
		(pad "1" smd circle
			(at -0.40005 0 180)
			(size 0 0)
			(layers "F.Cu" "F.Mask" "F.Paste")
			(net "P52V_FAN_4_BUFF_EN_R")
		)
		(pad "2" smd circle
			(at 0.40005 0 180)
			(size 0 0)
			(layers "F.Cu" "F.Mask" "F.Paste")
			(net "GND")
		)
	)
	(footprint ""
		(layer "F.Cu")
		(at 14.361922 -19.136868)
		(property "Reference" "R5130"
			(at 0 0 0)
			(layer "F.SilkS")
			(hide yes)
			(effects
				(font
					(size 1.27 1.27)
				)
			)
		)
		(property "Value" ""
			(at 0 0 0)
			(layer "F.Fab")
			(effects
				(font
					(size 1.27 1.27)
				)
			)
		)
		(duplicate_pad_numbers_are_jumpers no)
		(fp_line
			(start -0.7874 -0.4064)
			(end 0.7874 -0.4064)
			(stroke
				(width 0.1524)
				(type default)
			)
			(layer "F.SilkS")
		)
		(fp_line
			(start -0.7874 0.4064)
			(end -0.7874 -0.4064)
			(stroke
				(width 0.1524)
				(type default)
			)
			(layer "F.SilkS")
		)
		(fp_line
			(start 0.7874 -0.4064)
			(end 0.7874 0.4064)
			(stroke
				(width 0.1524)
				(type default)
			)
			(layer "F.SilkS")
		)
		(fp_line
			(start 0.7874 0.4064)
			(end -0.7874 0.4064)
			(stroke
				(width 0.1524)
				(type default)
			)
			(layer "F.SilkS")
		)
		(fp_line
			(start -0.67945 -0.305054)
			(end -0.12065 -0.305054)
			(stroke
				(width 0.1)
				(type default)
			)
			(layer "F.Fab")
		)
		(fp_line
			(start -0.67945 0.3048)
			(end -0.67945 -0.305054)
			(stroke
				(width 0.1)
				(type default)
			)
			(layer "F.Fab")
		)
		(fp_line
			(start -0.12065 -0.305054)
			(end -0.12065 -0.2794)
			(stroke
				(width 0.1)
				(type default)
			)
			(layer "F.Fab")
		)
		(fp_line
			(start -0.12065 -0.2794)
			(end 0.12065 -0.2794)
			(stroke
				(width 0.1)
				(type default)
			)
			(layer "F.Fab")
		)
		(fp_line
			(start -0.12065 0.2794)
			(end -0.12065 0.3048)
			(stroke
				(width 0.1)
				(type default)
			)
			(layer "F.Fab")
		)
		(fp_line
			(start -0.12065 0.3048)
			(end -0.67945 0.3048)
			(stroke
				(width 0.1)
				(type default)
			)
			(layer "F.Fab")
		)
		(fp_line
			(start 0.120396 0.2794)
			(end -0.12065 0.2794)
			(stroke
				(width 0.1)
				(type default)
			)
			(layer "F.Fab")
		)
		(fp_line
			(start 0.120396 0.3048)
			(end 0.120396 0.2794)
			(stroke
				(width 0.1)
				(type default)
			)
			(layer "F.Fab")
		)
		(fp_line
			(start 0.12065 -0.3048)
			(end 0.67945 -0.3048)
			(stroke
				(width 0.1)
				(type default)
			)
			(layer "F.Fab")
		)
		(fp_line
			(start 0.12065 -0.2794)
			(end 0.12065 -0.3048)
			(stroke
				(width 0.1)
				(type default)
			)
			(layer "F.Fab")
		)
		(fp_line
			(start 0.67945 -0.3048)
			(end 0.67945 0.3048)
			(stroke
				(width 0.1)
				(type default)
			)
			(layer "F.Fab")
		)
		(fp_line
			(start 0.67945 0.3048)
			(end 0.120396 0.3048)
			(stroke
				(width 0.1)
				(type default)
			)
			(layer "F.Fab")
		)
		(pad "1" smd circle
			(at -0.40005 0)
			(size 0 0)
			(layers "F.Cu" "F.Mask" "F.Paste")
			(net "FAN_4_PWM_IL_R")
		)
		(pad "2" smd circle
			(at 0.40005 0)
			(size 0 0)
			(layers "F.Cu" "F.Mask" "F.Paste")
			(net "FAN_4_PWM_IL")
		)
	)
	(footprint ""
		(layer "F.Cu")
		(at 43.561 -168.529 180)
		(property "Reference" "R5114"
			(at 0 0 180)
			(layer "F.SilkS")
			(hide yes)
			(effects
				(font
					(size 1.27 1.27)
				)
			)
		)
		(property "Value" ""
			(at 0 0 180)
			(layer "F.Fab")
			(effects
				(font
					(size 1.27 1.27)
				)
			)
		)
		(duplicate_pad_numbers_are_jumpers no)
		(fp_line
			(start 0.7874 0.4064)
			(end -0.7874 0.4064)
			(stroke
				(width 0.1524)
				(type default)
			)
			(layer "F.SilkS")
		)
		(fp_line
			(start 0.7874 -0.4064)
			(end 0.7874 0.4064)
			(stroke
				(width 0.1524)
				(type default)
			)
			(layer "F.SilkS")
		)
		(fp_line
			(start -0.7874 0.4064)
			(end -0.7874 -0.4064)
			(stroke
				(width 0.1524)
				(type default)
			)
			(layer "F.SilkS")
		)
		(fp_line
			(start -0.7874 -0.4064)
			(end 0.7874 -0.4064)
			(stroke
				(width 0.1524)
				(type default)
			)
			(layer "F.SilkS")
		)
		(fp_line
			(start 0.67945 0.3048)
			(end 0.120396 0.3048)
			(stroke
				(width 0.1)
				(type default)
			)
			(layer "F.Fab")
		)
		(fp_line
			(start 0.67945 -0.3048)
			(end 0.67945 0.3048)
			(stroke
				(width 0.1)
				(type default)
			)
			(layer "F.Fab")
		)
		(fp_line
			(start 0.12065 -0.2794)
			(end 0.12065 -0.3048)
			(stroke
				(width 0.1)
				(type default)
			)
			(layer "F.Fab")
		)
		(fp_line
			(start 0.12065 -0.3048)
			(end 0.67945 -0.3048)
			(stroke
				(width 0.1)
				(type default)
			)
			(layer "F.Fab")
		)
		(fp_line
			(start 0.120396 0.3048)
			(end 0.120396 0.2794)
			(stroke
				(width 0.1)
				(type default)
			)
			(layer "F.Fab")
		)
		(fp_line
			(start 0.120396 0.2794)
			(end -0.12065 0.2794)
			(stroke
				(width 0.1)
				(type default)
			)
			(layer "F.Fab")
		)
		(fp_line
			(start -0.12065 0.3048)
			(end -0.67945 0.3048)
			(stroke
				(width 0.1)
				(type default)
			)
			(layer "F.Fab")
		)
		(fp_line
			(start -0.12065 0.2794)
			(end -0.12065 0.3048)
			(stroke
				(width 0.1)
				(type default)
			)
			(layer "F.Fab")
		)
		(fp_line
			(start -0.12065 -0.2794)
			(end 0.12065 -0.2794)
			(stroke
				(width 0.1)
				(type default)
			)
			(layer "F.Fab")
		)
		(fp_line
			(start -0.12065 -0.305054)
			(end -0.12065 -0.2794)
			(stroke
				(width 0.1)
				(type default)
			)
			(layer "F.Fab")
		)
		(fp_line
			(start -0.67945 0.3048)
			(end -0.67945 -0.305054)
			(stroke
				(width 0.1)
				(type default)
			)
			(layer "F.Fab")
		)
		(fp_line
			(start -0.67945 -0.305054)
			(end -0.12065 -0.305054)
			(stroke
				(width 0.1)
				(type default)
			)
			(layer "F.Fab")
		)
		(pad "1" smd circle
			(at -0.40005 0 180)
			(size 0 0)
			(layers "F.Cu" "F.Mask" "F.Paste")
			(net "P3V3_AUX")
		)
		(pad "2" smd circle
			(at 0.40005 0 180)
			(size 0 0)
			(layers "F.Cu" "F.Mask" "F.Paste")
			(net "PCA9552_MB1_A2")
		)
	)
	(footprint ""
		(layer "F.Cu")
		(at 20.828 -173.736 180)
		(property "Reference" "R5671"
			(at 0 0 180)
			(layer "F.SilkS")
			(hide yes)
			(effects
				(font
					(size 1.27 1.27)
				)
			)
		)
		(property "Value" ""
			(at 0 0 180)
			(layer "F.Fab")
			(effects
				(font
					(size 1.27 1.27)
				)
			)
		)
		(duplicate_pad_numbers_are_jumpers no)
		(fp_line
			(start 0.7874 0.4064)
			(end -0.7874 0.4064)
			(stroke
				(width 0.1524)
				(type default)
			)
			(layer "F.SilkS")
		)
		(fp_line
			(start 0.7874 -0.4064)
			(end 0.7874 0.4064)
			(stroke
				(width 0.1524)
				(type default)
			)
			(layer "F.SilkS")
		)
		(fp_line
			(start -0.7874 0.4064)
			(end -0.7874 -0.4064)
			(stroke
				(width 0.1524)
				(type default)
			)
			(layer "F.SilkS")
		)
		(fp_line
			(start -0.7874 -0.4064)
			(end 0.7874 -0.4064)
			(stroke
				(width 0.1524)
				(type default)
			)
			(layer "F.SilkS")
		)
		(fp_line
			(start 0.67945 0.3048)
			(end 0.120396 0.3048)
			(stroke
				(width 0.1)
				(type default)
			)
			(layer "F.Fab")
		)
		(fp_line
			(start 0.67945 -0.3048)
			(end 0.67945 0.3048)
			(stroke
				(width 0.1)
				(type default)
			)
			(layer "F.Fab")
		)
		(fp_line
			(start 0.12065 -0.2794)
			(end 0.12065 -0.3048)
			(stroke
				(width 0.1)
				(type default)
			)
			(layer "F.Fab")
		)
		(fp_line
			(start 0.12065 -0.3048)
			(end 0.67945 -0.3048)
			(stroke
				(width 0.1)
				(type default)
			)
			(layer "F.Fab")
		)
		(fp_line
			(start 0.120396 0.3048)
			(end 0.120396 0.2794)
			(stroke
				(width 0.1)
				(type default)
			)
			(layer "F.Fab")
		)
		(fp_line
			(start 0.120396 0.2794)
			(end -0.12065 0.2794)
			(stroke
				(width 0.1)
				(type default)
			)
			(layer "F.Fab")
		)
		(fp_line
			(start -0.12065 0.3048)
			(end -0.67945 0.3048)
			(stroke
				(width 0.1)
				(type default)
			)
			(layer "F.Fab")
		)
		(fp_line
			(start -0.12065 0.2794)
			(end -0.12065 0.3048)
			(stroke
				(width 0.1)
				(type default)
			)
			(layer "F.Fab")
		)
		(fp_line
			(start -0.12065 -0.2794)
			(end 0.12065 -0.2794)
			(stroke
				(width 0.1)
				(type default)
			)
			(layer "F.Fab")
		)
		(fp_line
			(start -0.12065 -0.305054)
			(end -0.12065 -0.2794)
			(stroke
				(width 0.1)
				(type default)
			)
			(layer "F.Fab")
		)
		(fp_line
			(start -0.67945 0.3048)
			(end -0.67945 -0.305054)
			(stroke
				(width 0.1)
				(type default)
			)
			(layer "F.Fab")
		)
		(fp_line
			(start -0.67945 -0.305054)
			(end -0.12065 -0.305054)
			(stroke
				(width 0.1)
				(type default)
			)
			(layer "F.Fab")
		)
		(pad "1" smd circle
			(at -0.40005 0 180)
			(size 0 0)
			(layers "F.Cu" "F.Mask" "F.Paste")
			(net "P3V3_AUX")
		)
		(pad "2" smd circle
			(at 0.40005 0 180)
			(size 0 0)
			(layers "F.Cu" "F.Mask" "F.Paste")
			(net "FM_BOARD_SKU_ID1")
		)
	)
)
